# BASEBOARD_FAB2 (Tioga Pass) — schematic netlist excerpt (pin names and nets, part order shuffled) for the footprints in the layout excerpt that follows; sources: Cadence DE-HDL packaged netlist, KiCad conversion of Wiwynn_Tioga_Pass_MB.brd

R2P12  RES  0.0 5% EMPTY  pkg 0402  page 89 : A = IRQ_DIMM_SAVE_LVT3_N ; B = FM_ADR_SMI_GPIO_N
R1D19  RES  10.0K 1% CHIP  pkg 0402  page 200 : A = A_HSC_HIGH ; B = AGND_HSC
R8G9  RES  0.0 5% EMPTY  pkg 0402  page 189 : A = JTAG_PCH_GBE_TRST_N ; B = JTAG_TRST_N

(kicad_pcb
	(version 20260206)
	(generator "pcbnew")
	(generator_version "10.0")
	(general
		(thickness 1.6)
		(legacy_teardrops no)
	)
	(paper "A4")
	(title_block
		(title "Wiwynn_Tioga_Pass_MB.brd")
		(comment 1 "Tioga Pass / footprints 1013-1015 of 4770")
	)
	(layers
		(0 "F.Cu" signal "TOP")
		(4 "In1.Cu" signal "L2GND")
		(6 "In2.Cu" signal "L3")
		(8 "In3.Cu" signal "L4GND")
		(10 "In4.Cu" signal "L5")
		(12 "In5.Cu" signal "L6GND")
		(14 "In6.Cu" signal "L7VCC")
		(16 "In7.Cu" signal "L8VCC")
		(18 "In8.Cu" signal "L9GND")
		(20 "In9.Cu" signal "L10")
		(22 "In10.Cu" signal "L11GND")
		(24 "In11.Cu" signal "L12")
		(26 "In12.Cu" signal "L13GND")
		(2 "B.Cu" signal "BOTTOM")
		(9 "F.Adhes" user "F.Adhesive")
		(11 "B.Adhes" user "B.Adhesive")
		(13 "F.Paste" user "Package Geometry/Pastemask Top")
		(15 "B.Paste" user "Package Geometry/Pastemask Bottom")
		(5 "F.SilkS" user "Ref Des/Silkscreen Top")
		(7 "B.SilkS" user "Ref Des/Silkscreen Bottom")
		(1 "F.Mask" user "Board Geometry/Soldermask Top")
		(3 "B.Mask" user "Board Geometry/Soldermask Bottom")
		(17 "Dwgs.User" user "User.Drawings")
		(19 "Cmts.User" user "User.Comments")
		(21 "Eco1.User" user "User.Eco1")
		(23 "Eco2.User" user "User.Eco2")
		(25 "Edge.Cuts" user "Board Geometry/Outline")
		(27 "Margin" user)
		(31 "F.CrtYd" user "Package Geometry/Place Bound Top")
		(29 "B.CrtYd" user "Package Geometry/Place Bound Bottom")
		(35 "F.Fab" user "Ref Des/Assembly Top")
		(33 "B.Fab" user "Ref Des/Assembly Bottom")
	)
	(footprint ""
		(layer "F.Cu")
		(at 22.225 -81.788)
		(property "Reference" "R1D19"
			(at 0 0 0)
			(layer "F.SilkS")
			(hide yes)
			(effects
				(font
					(size 1.27 1.27)
				)
			)
		)
		(property "Value" ""
			(at 0 0 0)
			(layer "F.Fab")
			(effects
				(font
					(size 1.27 1.27)
				)
			)
		)
		(duplicate_pad_numbers_are_jumpers no)
		(fp_poly
			(pts
				(xy -0.2794 -0.1016) (xy 0.2794 -0.1016) (xy 0.2794 0.9906) (xy -0.2794 0.9906)
			)
			(stroke
				(width 0)
				(type default)
			)
			(fill no)
			(layer "F.CrtYd")
		)
		(fp_line
			(start -0.2794 -0.1016)
			(end -0.2794 0.9906)
			(stroke
				(width 0.1)
				(type default)
			)
			(layer "F.Fab")
		)
		(fp_line
			(start -0.2794 0.9906)
			(end 0.2794 0.9906)
			(stroke
				(width 0.1)
				(type default)
			)
			(layer "F.Fab")
		)
		(fp_line
			(start 0.2794 -0.1016)
			(end -0.2794 -0.1016)
			(stroke
				(width 0.1)
				(type default)
			)
			(layer "F.Fab")
		)
		(fp_line
			(start 0.2794 0.9906)
			(end 0.2794 -0.1016)
			(stroke
				(width 0.1)
				(type default)
			)
			(layer "F.Fab")
		)
		(pad "1" smd rect
			(at 0 0)
			(size 0.508 0.508)
			(layers "F.Cu" "F.Mask" "F.Paste")
			(net "A_HSC_HIGH")
		)
		(pad "2" smd rect
			(at 0 0.889)
			(size 0.508 0.508)
			(layers "F.Cu" "F.Mask" "F.Paste")
			(net "AGND_HSC")
		)
		(zone
			(layer "F.Cu")
			(hatch none 0.5)
			(connect_pads
				(clearance 0)
			)
			(min_thickness 0.25)
			(keepout
				(tracks allowed)
				(vias not_allowed)
				(pads allowed)
				(copperpour not_allowed)
				(footprints allowed)
			)
			(placement
				(enabled no)
				(sheetname "")
			)
			(fill
				(thermal_gap 0.5)
				(thermal_bridge_width 0.5)
				(island_removal_mode 0)
			)
			(polygon
				(pts
					(xy 21.971 -81.534) (xy 22.479 -81.534) (xy 22.479 -81.153) (xy 21.971 -81.153)
				)
			)
		)
		(zone
			(layer "F.Cu")
			(hatch none 0.5)
			(connect_pads
				(clearance 0)
			)
			(min_thickness 0.25)
			(keepout
				(tracks not_allowed)
				(vias allowed)
				(pads allowed)
				(copperpour not_allowed)
				(footprints allowed)
			)
			(placement
				(enabled no)
				(sheetname "")
			)
			(fill
				(thermal_gap 0.5)
				(thermal_bridge_width 0.5)
				(island_removal_mode 0)
			)
			(polygon
				(pts
					(xy 21.971 -81.153) (xy 22.479 -81.153) (xy 22.479 -81.534) (xy 21.971 -81.534)
				)
			)
		)
	)
	(footprint ""
		(layer "F.Cu")
		(at 410.7688 -99.3394 90)
		(property "Reference" "R2P12"
			(at 0 0 90)
			(layer "F.SilkS")
			(hide yes)
			(effects
				(font
					(size 1.27 1.27)
				)
			)
		)
		(property "Value" ""
			(at 0 0 90)
			(layer "F.Fab")
			(effects
				(font
					(size 1.27 1.27)
				)
			)
		)
		(duplicate_pad_numbers_are_jumpers no)
		(fp_poly
			(pts
				(xy -0.2794 -0.1016) (xy 0.2794 -0.1016) (xy 0.2794 0.9906) (xy -0.2794 0.9906)
			)
			(stroke
				(width 0)
				(type default)
			)
			(fill no)
			(layer "F.CrtYd")
		)
		(fp_line
			(start 0.2794 -0.1016)
			(end -0.2794 -0.1016)
			(stroke
				(width 0.1)
				(type default)
			)
			(layer "F.Fab")
		)
		(fp_line
			(start -0.2794 -0.1016)
			(end -0.2794 0.9906)
			(stroke
				(width 0.1)
				(type default)
			)
			(layer "F.Fab")
		)
		(fp_line
			(start 0.2794 0.9906)
			(end 0.2794 -0.1016)
			(stroke
				(width 0.1)
				(type default)
			)
			(layer "F.Fab")
		)
		(fp_line
			(start -0.2794 0.9906)
			(end 0.2794 0.9906)
			(stroke
				(width 0.1)
				(type default)
			)
			(layer "F.Fab")
		)
		(pad "1" smd rect
			(at 0 0 90)
			(size 0.508 0.508)
			(layers "F.Cu" "F.Mask" "F.Paste")
			(net "IRQ_DIMM_SAVE_LVT3_N")
		)
		(pad "2" smd rect
			(at 0 0.889 90)
			(size 0.508 0.508)
			(layers "F.Cu" "F.Mask" "F.Paste")
			(net "FM_ADR_SMI_GPIO_N")
		)
		(zone
			(layer "F.Cu")
			(hatch none 0.5)
			(connect_pads
				(clearance 0)
			)
			(min_thickness 0.25)
			(keepout
				(tracks allowed)
				(vias not_allowed)
				(pads allowed)
				(copperpour not_allowed)
				(footprints allowed)
			)
			(placement
				(enabled no)
				(sheetname "")
			)
			(fill
				(thermal_gap 0.5)
				(thermal_bridge_width 0.5)
				(island_removal_mode 0)
			)
			(polygon
				(pts
					(xy 411.0228 -99.0854) (xy 411.0228 -99.5934) (xy 411.4038 -99.5934) (xy 411.4038 -99.0854)
				)
			)
		)
		(zone
			(layer "F.Cu")
			(hatch none 0.5)
			(connect_pads
				(clearance 0)
			)
			(min_thickness 0.25)
			(keepout
				(tracks not_allowed)
				(vias allowed)
				(pads allowed)
				(copperpour not_allowed)
				(footprints allowed)
			)
			(placement
				(enabled no)
				(sheetname "")
			)
			(fill
				(thermal_gap 0.5)
				(thermal_bridge_width 0.5)
				(island_removal_mode 0)
			)
			(polygon
				(pts
					(xy 411.4038 -99.0854) (xy 411.4038 -99.5934) (xy 411.0228 -99.5934) (xy 411.0228 -99.0854)
				)
			)
		)
	)
	(footprint ""
		(layer "F.Cu")
		(at 391.16 -0.254)
		(property "Reference" "R8G9"
			(at 0 0 0)
			(layer "F.SilkS")
			(hide yes)
			(effects
				(font
					(size 1.27 1.27)
				)
			)
		)
		(property "Value" ""
			(at 0 0 0)
			(layer "F.Fab")
			(effects
				(font
					(size 1.27 1.27)
				)
			)
		)
		(duplicate_pad_numbers_are_jumpers no)
		(fp_poly
			(pts
				(xy -0.2794 -0.1016) (xy 0.2794 -0.1016) (xy 0.2794 0.9906) (xy -0.2794 0.9906)
			)
			(stroke
				(width 0)
				(type default)
			)
			(fill no)
			(layer "F.CrtYd")
		)
		(fp_line
			(start -0.2794 -0.1016)
			(end -0.2794 0.9906)
			(stroke
				(width 0.1)
				(type default)
			)
			(layer "F.Fab")
		)
		(fp_line
			(start -0.2794 0.9906)
			(end 0.2794 0.9906)
			(stroke
				(width 0.1)
				(type default)
			)
			(layer "F.Fab")
		)
		(fp_line
			(start 0.2794 -0.1016)
			(end -0.2794 -0.1016)
			(stroke
				(width 0.1)
				(type default)
			)
			(layer "F.Fab")
		)
		(fp_line
			(start 0.2794 0.9906)
			(end 0.2794 -0.1016)
			(stroke
				(width 0.1)
				(type default)
			)
			(layer "F.Fab")
		)
		(pad "1" smd rect
			(at 0 0)
			(size 0.508 0.508)
			(layers "F.Cu" "F.Mask" "F.Paste")
			(net "JTAG_PCH_GBE_TRST_N")
		)
		(pad "2" smd rect
			(at 0 0.889)
			(size 0.508 0.508)
			(layers "F.Cu" "F.Mask" "F.Paste")
			(net "JTAG_TRST_N")
		)
		(zone
			(layer "F.Cu")
			(hatch none 0.5)
			(connect_pads
				(clearance 0)
			)
			(min_thickness 0.25)
			(keepout
				(tracks allowed)
				(vias not_allowed)
				(pads allowed)
				(copperpour not_allowed)
				(footprints allowed)
			)
			(placement
				(enabled no)
				(sheetname "")
			)
			(fill
				(thermal_gap 0.5)
				(thermal_bridge_width 0.5)
				(island_removal_mode 0)
			)
			(polygon
				(pts
					(xy 390.906 0) (xy 391.414 0) (xy 391.414 0.381) (xy 390.906 0.381)
				)
			)
		)
		(zone
			(layer "F.Cu")
			(hatch none 0.5)
			(connect_pads
				(clearance 0)
			)
			(min_thickness 0.25)
			(keepout
				(tracks not_allowed)
				(vias allowed)
				(pads allowed)
				(copperpour not_allowed)
				(footprints allowed)
			)
			(placement
				(enabled no)
				(sheetname "")
			)
			(fill
				(thermal_gap 0.5)
				(thermal_bridge_width 0.5)
				(island_removal_mode 0)
			)
			(polygon
				(pts
					(xy 390.906 0.381) (xy 391.414 0.381) (xy 391.414 0) (xy 390.906 0)
				)
			)
		)
	)
)
